(kicad_pcb
	(version 20260206)
	(generator "pcbnew")
	(generator_version "10.0")
	(general
		(thickness 1.6)
		(legacy_teardrops no)
	)
	(paper "A4")
	(title_block
		(title "01162023_DA0F0TEBIF0_F0T_Expander_BD_F_brd_V02_OCP.brd")
		(comment 1 "Grand Teton / footprints 452-457 of 9728")
	)
	(layers
		(0 "F.Cu" signal "TOP")
		(4 "In1.Cu" signal "GND")
		(6 "In2.Cu" signal "VCC")
		(8 "In3.Cu" signal "VCC1")
		(10 "In4.Cu" signal "GND1")
		(12 "In5.Cu" signal "IN1")
		(14 "In6.Cu" signal "GND2")
		(16 "In7.Cu" signal "IN2")
		(18 "In8.Cu" signal "GND3")
		(20 "In9.Cu" signal "IN3")
		(22 "In10.Cu" signal "GND4")
		(24 "In11.Cu" signal "IN4")
		(26 "In12.Cu" signal "GND5")
		(28 "In13.Cu" signal "IN5")
		(30 "In14.Cu" signal "GND6")
		(32 "In15.Cu" signal "IN6")
		(34 "In16.Cu" signal "GND7")
		(2 "B.Cu" signal "BOTTOM")
		(9 "F.Adhes" user "F.Adhesive")
		(11 "B.Adhes" user "B.Adhesive")
		(13 "F.Paste" user "Package Geometry/Pastemask Top")
		(15 "B.Paste" user "Package Geometry/Pastemask Bottom")
		(5 "F.SilkS" user "Ref Des/Silkscreen Top")
		(7 "B.SilkS" user "Ref Des/Silkscreen Bottom")
		(1 "F.Mask" user "Board Geometry/Soldermask Top")
		(3 "B.Mask" user "Board Geometry/Soldermask Bottom")
		(17 "Dwgs.User" user "User.Drawings")
		(19 "Cmts.User" user "User.Comments")
		(21 "Eco1.User" user "User.Eco1")
		(23 "Eco2.User" user "User.Eco2")
		(25 "Edge.Cuts" user "Board Geometry/Outline")
		(27 "Margin" user)
		(31 "F.CrtYd" user "Package Geometry/Place Bound Top")
		(29 "B.CrtYd" user "Package Geometry/Place Bound Bottom")
		(35 "F.Fab" user "Ref Des/Assembly Top")
		(33 "B.Fab" user "Ref Des/Assembly Bottom")
	)
	(footprint ""
		(layer "F.Cu")
		(at 378.852684 -89.9668 180)
		(property "Reference" "R1759"
			(at 0 0 180)
			(layer "F.SilkS")
			(hide yes)
			(effects
				(font
					(size 1.27 1.27)
				)
			)
		)
		(property "Value" ""
			(at 0 0 180)
			(layer "F.Fab")
			(effects
				(font
					(size 1.27 1.27)
				)
			)
		)
		(duplicate_pad_numbers_are_jumpers no)
		(fp_line
			(start 0.7874 0.4064)
			(end -0.7874 0.4064)
			(stroke
				(width 0.1524)
				(type default)
			)
			(layer "F.SilkS")
		)
		(fp_line
			(start 0.7874 -0.4064)
			(end 0.7874 0.4064)
			(stroke
				(width 0.1524)
				(type default)
			)
			(layer "F.SilkS")
		)
		(fp_line
			(start -0.7874 0.4064)
			(end -0.7874 -0.4064)
			(stroke
				(width 0.1524)
				(type default)
			)
			(layer "F.SilkS")
		)
		(fp_line
			(start -0.7874 -0.4064)
			(end 0.7874 -0.4064)
			(stroke
				(width 0.1524)
				(type default)
			)
			(layer "F.SilkS")
		)
		(fp_line
			(start 0.67945 0.3048)
			(end 0.120396 0.3048)
			(stroke
				(width 0.1)
				(type default)
			)
			(layer "F.Fab")
		)
		(fp_line
			(start 0.67945 -0.3048)
			(end 0.67945 0.3048)
			(stroke
				(width 0.1)
				(type default)
			)
			(layer "F.Fab")
		)
		(fp_line
			(start 0.12065 -0.2794)
			(end 0.12065 -0.3048)
			(stroke
				(width 0.1)
				(type default)
			)
			(layer "F.Fab")
		)
		(fp_line
			(start 0.12065 -0.3048)
			(end 0.67945 -0.3048)
			(stroke
				(width 0.1)
				(type default)
			)
			(layer "F.Fab")
		)
		(fp_line
			(start 0.120396 0.3048)
			(end 0.120396 0.2794)
			(stroke
				(width 0.1)
				(type default)
			)
			(layer "F.Fab")
		)
		(fp_line
			(start 0.120396 0.2794)
			(end -0.12065 0.2794)
			(stroke
				(width 0.1)
				(type default)
			)
			(layer "F.Fab")
		)
		(fp_line
			(start -0.12065 0.3048)
			(end -0.67945 0.3048)
			(stroke
				(width 0.1)
				(type default)
			)
			(layer "F.Fab")
		)
		(fp_line
			(start -0.12065 0.2794)
			(end -0.12065 0.3048)
			(stroke
				(width 0.1)
				(type default)
			)
			(layer "F.Fab")
		)
		(fp_line
			(start -0.12065 -0.2794)
			(end 0.12065 -0.2794)
			(stroke
				(width 0.1)
				(type default)
			)
			(layer "F.Fab")
		)
		(fp_line
			(start -0.12065 -0.305054)
			(end -0.12065 -0.2794)
			(stroke
				(width 0.1)
				(type default)
			)
			(layer "F.Fab")
		)
		(fp_line
			(start -0.67945 0.3048)
			(end -0.67945 -0.305054)
			(stroke
				(width 0.1)
				(type default)
			)
			(layer "F.Fab")
		)
		(fp_line
			(start -0.67945 -0.305054)
			(end -0.12065 -0.305054)
			(stroke
				(width 0.1)
				(type default)
			)
			(layer "F.Fab")
		)
		(pad "1" smd circle
			(at -0.40005 0 180)
			(size 0 0)
			(layers "F.Cu" "F.Mask" "F.Paste")
			(net "BIC_I2C6_MUX_A1")
		)
		(pad "2" smd circle
			(at 0.40005 0 180)
			(size 0 0)
			(layers "F.Cu" "F.Mask" "F.Paste")
			(net "GND")
		)
	)
	(footprint ""
		(layer "F.Cu")
		(at 376.809 -190.627)
		(property "Reference" "R4656"
			(at 0 0 0)
			(layer "F.SilkS")
			(hide yes)
			(effects
				(font
					(size 1.27 1.27)
				)
			)
		)
		(property "Value" ""
			(at 0 0 0)
			(layer "F.Fab")
			(effects
				(font
					(size 1.27 1.27)
				)
			)
		)
		(duplicate_pad_numbers_are_jumpers no)
		(fp_line
			(start -0.7874 -0.4064)
			(end 0.7874 -0.4064)
			(stroke
				(width 0.1524)
				(type default)
			)
			(layer "F.SilkS")
		)
		(fp_line
			(start -0.7874 0.4064)
			(end -0.7874 -0.4064)
			(stroke
				(width 0.1524)
				(type default)
			)
			(layer "F.SilkS")
		)
		(fp_line
			(start 0.7874 -0.4064)
			(end 0.7874 0.4064)
			(stroke
				(width 0.1524)
				(type default)
			)
			(layer "F.SilkS")
		)
		(fp_line
			(start 0.7874 0.4064)
			(end -0.7874 0.4064)
			(stroke
				(width 0.1524)
				(type default)
			)
			(layer "F.SilkS")
		)
		(fp_line
			(start -0.67945 -0.305054)
			(end -0.12065 -0.305054)
			(stroke
				(width 0.1)
				(type default)
			)
			(layer "F.Fab")
		)
		(fp_line
			(start -0.67945 0.3048)
			(end -0.67945 -0.305054)
			(stroke
				(width 0.1)
				(type default)
			)
			(layer "F.Fab")
		)
		(fp_line
			(start -0.12065 -0.305054)
			(end -0.12065 -0.2794)
			(stroke
				(width 0.1)
				(type default)
			)
			(layer "F.Fab")
		)
		(fp_line
			(start -0.12065 -0.2794)
			(end 0.12065 -0.2794)
			(stroke
				(width 0.1)
				(type default)
			)
			(layer "F.Fab")
		)
		(fp_line
			(start -0.12065 0.2794)
			(end -0.12065 0.3048)
			(stroke
				(width 0.1)
				(type default)
			)
			(layer "F.Fab")
		)
		(fp_line
			(start -0.12065 0.3048)
			(end -0.67945 0.3048)
			(stroke
				(width 0.1)
				(type default)
			)
			(layer "F.Fab")
		)
		(fp_line
			(start 0.120396 0.2794)
			(end -0.12065 0.2794)
			(stroke
				(width 0.1)
				(type default)
			)
			(layer "F.Fab")
		)
		(fp_line
			(start 0.120396 0.3048)
			(end 0.120396 0.2794)
			(stroke
				(width 0.1)
				(type default)
			)
			(layer "F.Fab")
		)
		(fp_line
			(start 0.12065 -0.3048)
			(end 0.67945 -0.3048)
			(stroke
				(width 0.1)
				(type default)
			)
			(layer "F.Fab")
		)
		(fp_line
			(start 0.12065 -0.2794)
			(end 0.12065 -0.3048)
			(stroke
				(width 0.1)
				(type default)
			)
			(layer "F.Fab")
		)
		(fp_line
			(start 0.67945 -0.3048)
			(end 0.67945 0.3048)
			(stroke
				(width 0.1)
				(type default)
			)
			(layer "F.Fab")
		)
		(fp_line
			(start 0.67945 0.3048)
			(end 0.120396 0.3048)
			(stroke
				(width 0.1)
				(type default)
			)
			(layer "F.Fab")
		)
		(pad "1" smd circle
			(at -0.40005 0)
			(size 0 0)
			(layers "F.Cu" "F.Mask" "F.Paste")
			(net "GND")
		)
		(pad "2" smd circle
			(at 0.40005 0)
			(size 0 0)
			(layers "F.Cu" "F.Mask" "F.Paste")
			(net "PCA9555_1_PEX0_A0")
		)
	)
	(footprint ""
		(layer "F.Cu")
		(at 32.709104 -26.03373)
		(property "Reference" "R4054"
			(at 0 0 0)
			(layer "F.SilkS")
			(hide yes)
			(effects
				(font
					(size 1.27 1.27)
				)
			)
		)
		(property "Value" ""
			(at 0 0 0)
			(layer "F.Fab")
			(effects
				(font
					(size 1.27 1.27)
				)
			)
		)
		(duplicate_pad_numbers_are_jumpers no)
		(fp_line
			(start -0.7874 -0.4064)
			(end 0.7874 -0.4064)
			(stroke
				(width 0.1524)
				(type default)
			)
			(layer "F.SilkS")
		)
		(fp_line
			(start -0.7874 0.4064)
			(end -0.7874 -0.4064)
			(stroke
				(width 0.1524)
				(type default)
			)
			(layer "F.SilkS")
		)
		(fp_line
			(start 0.7874 -0.4064)
			(end 0.7874 0.4064)
			(stroke
				(width 0.1524)
				(type default)
			)
			(layer "F.SilkS")
		)
		(fp_line
			(start 0.7874 0.4064)
			(end -0.7874 0.4064)
			(stroke
				(width 0.1524)
				(type default)
			)
			(layer "F.SilkS")
		)
		(fp_line
			(start -0.67945 -0.305054)
			(end -0.12065 -0.305054)
			(stroke
				(width 0.1)
				(type default)
			)
			(layer "F.Fab")
		)
		(fp_line
			(start -0.67945 0.3048)
			(end -0.67945 -0.305054)
			(stroke
				(width 0.1)
				(type default)
			)
			(layer "F.Fab")
		)
		(fp_line
			(start -0.12065 -0.305054)
			(end -0.12065 -0.2794)
			(stroke
				(width 0.1)
				(type default)
			)
			(layer "F.Fab")
		)
		(fp_line
			(start -0.12065 -0.2794)
			(end 0.12065 -0.2794)
			(stroke
				(width 0.1)
				(type default)
			)
			(layer "F.Fab")
		)
		(fp_line
			(start -0.12065 0.2794)
			(end -0.12065 0.3048)
			(stroke
				(width 0.1)
				(type default)
			)
			(layer "F.Fab")
		)
		(fp_line
			(start -0.12065 0.3048)
			(end -0.67945 0.3048)
			(stroke
				(width 0.1)
				(type default)
			)
			(layer "F.Fab")
		)
		(fp_line
			(start 0.120396 0.2794)
			(end -0.12065 0.2794)
			(stroke
				(width 0.1)
				(type default)
			)
			(layer "F.Fab")
		)
		(fp_line
			(start 0.120396 0.3048)
			(end 0.120396 0.2794)
			(stroke
				(width 0.1)
				(type default)
			)
			(layer "F.Fab")
		)
		(fp_line
			(start 0.12065 -0.3048)
			(end 0.67945 -0.3048)
			(stroke
				(width 0.1)
				(type default)
			)
			(layer "F.Fab")
		)
		(fp_line
			(start 0.12065 -0.2794)
			(end 0.12065 -0.3048)
			(stroke
				(width 0.1)
				(type default)
			)
			(layer "F.Fab")
		)
		(fp_line
			(start 0.67945 -0.3048)
			(end 0.67945 0.3048)
			(stroke
				(width 0.1)
				(type default)
			)
			(layer "F.Fab")
		)
		(fp_line
			(start 0.67945 0.3048)
			(end 0.120396 0.3048)
			(stroke
				(width 0.1)
				(type default)
			)
			(layer "F.Fab")
		)
		(pad "1" smd circle
			(at -0.40005 0)
			(size 0 0)
			(layers "F.Cu" "F.Mask" "F.Paste")
			(net "P3V3_AUX")
		)
		(pad "2" smd circle
			(at 0.40005 0)
			(size 0 0)
			(layers "F.Cu" "F.Mask" "F.Paste")
			(net "PRSNT_SSD1_R_N")
		)
	)
	(footprint ""
		(layer "F.Cu")
		(at 9.1059 -394.13942 -90)
		(property "Reference" "R6739"
			(at 0 0 270)
			(layer "F.SilkS")
			(hide yes)
			(effects
				(font
					(size 1.27 1.27)
				)
			)
		)
		(property "Value" ""
			(at 0 0 270)
			(layer "F.Fab")
			(effects
				(font
					(size 1.27 1.27)
				)
			)
		)
		(duplicate_pad_numbers_are_jumpers no)
		(fp_line
			(start -0.7874 0.4064)
			(end -0.7874 -0.4064)
			(stroke
				(width 0.1524)
				(type default)
			)
			(layer "F.SilkS")
		)
		(fp_line
			(start 0.7874 0.4064)
			(end -0.7874 0.4064)
			(stroke
				(width 0.1524)
				(type default)
			)
			(layer "F.SilkS")
		)
		(fp_line
			(start -0.7874 -0.4064)
			(end 0.7874 -0.4064)
			(stroke
				(width 0.1524)
				(type default)
			)
			(layer "F.SilkS")
		)
		(fp_line
			(start 0.7874 -0.4064)
			(end 0.7874 0.4064)
			(stroke
				(width 0.1524)
				(type default)
			)
			(layer "F.SilkS")
		)
		(fp_line
			(start -0.67945 0.3048)
			(end -0.67945 -0.305054)
			(stroke
				(width 0.1)
				(type default)
			)
			(layer "F.Fab")
		)
		(fp_line
			(start -0.12065 0.3048)
			(end -0.67945 0.3048)
			(stroke
				(width 0.1)
				(type default)
			)
			(layer "F.Fab")
		)
		(fp_line
			(start 0.120396 0.3048)
			(end 0.120396 0.2794)
			(stroke
				(width 0.1)
				(type default)
			)
			(layer "F.Fab")
		)
		(fp_line
			(start 0.67945 0.3048)
			(end 0.120396 0.3048)
			(stroke
				(width 0.1)
				(type default)
			)
			(layer "F.Fab")
		)
		(fp_line
			(start -0.12065 0.2794)
			(end -0.12065 0.3048)
			(stroke
				(width 0.1)
				(type default)
			)
			(layer "F.Fab")
		)
		(fp_line
			(start 0.120396 0.2794)
			(end -0.12065 0.2794)
			(stroke
				(width 0.1)
				(type default)
			)
			(layer "F.Fab")
		)
		(fp_line
			(start -0.12065 -0.2794)
			(end 0.12065 -0.2794)
			(stroke
				(width 0.1)
				(type default)
			)
			(layer "F.Fab")
		)
		(fp_line
			(start 0.12065 -0.2794)
			(end 0.12065 -0.3048)
			(stroke
				(width 0.1)
				(type default)
			)
			(layer "F.Fab")
		)
		(fp_line
			(start 0.12065 -0.3048)
			(end 0.67945 -0.3048)
			(stroke
				(width 0.1)
				(type default)
			)
			(layer "F.Fab")
		)
		(fp_line
			(start 0.67945 -0.3048)
			(end 0.67945 0.3048)
			(stroke
				(width 0.1)
				(type default)
			)
			(layer "F.Fab")
		)
		(fp_line
			(start -0.67945 -0.305054)
			(end -0.12065 -0.305054)
			(stroke
				(width 0.1)
				(type default)
			)
			(layer "F.Fab")
		)
		(fp_line
			(start -0.12065 -0.305054)
			(end -0.12065 -0.2794)
			(stroke
				(width 0.1)
				(type default)
			)
			(layer "F.Fab")
		)
		(pad "1" smd circle
			(at -0.40005 0 270)
			(size 0 0)
			(layers "F.Cu" "F.Mask" "F.Paste")
			(net "GND")
		)
		(pad "2" smd circle
			(at 0.40005 0 270)
			(size 0 0)
			(layers "F.Cu" "F.Mask" "F.Paste")
			(net "BIC_USB_8042_HUB_HS_SUSPEND")
		)
	)
	(footprint ""
		(layer "F.Cu")
		(at 33.040066 -259.834634 180)
		(property "Reference" "C3048"
			(at 0 0 180)
			(layer "F.SilkS")
			(hide yes)
			(effects
				(font
					(size 1.27 1.27)
				)
			)
		)
		(property "Value" ""
			(at 0 0 180)
			(layer "F.Fab")
			(effects
				(font
					(size 1.27 1.27)
				)
			)
		)
		(duplicate_pad_numbers_are_jumpers no)
		(fp_line
			(start 1.2954 0.5842)
			(end -1.2954 0.5842)
			(stroke
				(width 0.1524)
				(type default)
			)
			(layer "F.SilkS")
		)
		(fp_line
			(start 1.2954 -0.5842)
			(end 1.2954 0.5842)
			(stroke
				(width 0.1524)
				(type default)
			)
			(layer "F.SilkS")
		)
		(fp_line
			(start -1.2954 0.5842)
			(end -1.2954 -0.5842)
			(stroke
				(width 0.1524)
				(type default)
			)
			(layer "F.SilkS")
		)
		(fp_line
			(start -1.2954 -0.5842)
			(end 1.2954 -0.5842)
			(stroke
				(width 0.1524)
				(type default)
			)
			(layer "F.SilkS")
		)
		(fp_line
			(start 1.1938 0.4064)
			(end 0.8636 0.4064)
			(stroke
				(width 0.1)
				(type default)
			)
			(layer "F.Fab")
		)
		(fp_line
			(start 1.1938 -0.4064)
			(end 1.1938 0.4064)
			(stroke
				(width 0.1)
				(type default)
			)
			(layer "F.Fab")
		)
		(fp_line
			(start 0.8636 0.4572)
			(end -0.8636 0.4572)
			(stroke
				(width 0.1)
				(type default)
			)
			(layer "F.Fab")
		)
		(fp_line
			(start 0.8636 0.4064)
			(end 0.8636 0.4572)
			(stroke
				(width 0.1)
				(type default)
			)
			(layer "F.Fab")
		)
		(fp_line
			(start 0.8636 -0.4064)
			(end 1.1938 -0.4064)
			(stroke
				(width 0.1)
				(type default)
			)
			(layer "F.Fab")
		)
		(fp_line
			(start 0.8636 -0.4572)
			(end 0.8636 -0.4064)
			(stroke
				(width 0.1)
				(type default)
			)
			(layer "F.Fab")
		)
		(fp_line
			(start -0.8636 0.4572)
			(end -0.8636 0.4064)
			(stroke
				(width 0.1)
				(type default)
			)
			(layer "F.Fab")
		)
		(fp_line
			(start -0.8636 0.4064)
			(end -1.1938 0.4064)
			(stroke
				(width 0.1)
				(type default)
			)
			(layer "F.Fab")
		)
		(fp_line
			(start -0.8636 -0.4064)
			(end -0.8636 -0.4572)
			(stroke
				(width 0.1)
				(type default)
			)
			(layer "F.Fab")
		)
		(fp_line
			(start -0.8636 -0.4572)
			(end 0.8636 -0.4572)
			(stroke
				(width 0.1)
				(type default)
			)
			(layer "F.Fab")
		)
		(fp_line
			(start -1.1938 0.4064)
			(end -1.1938 -0.4064)
			(stroke
				(width 0.1)
				(type default)
			)
			(layer "F.Fab")
		)
		(fp_line
			(start -1.1938 -0.4064)
			(end -0.8636 -0.4064)
			(stroke
				(width 0.1)
				(type default)
			)
			(layer "F.Fab")
		)
		(pad "1" smd rect
			(at -0.7366 0 90)
			(size 0.7112 0.8128)
			(layers "F.Cu" "F.Mask" "F.Paste")
			(net "PCEPLL3_VDDA18_PEX0_R")
		)
		(pad "2" smd rect
			(at 0.7366 0 90)
			(size 0.7112 0.8128)
			(layers "F.Cu" "F.Mask" "F.Paste")
			(net "GND")
		)
	)
	(footprint ""
		(layer "F.Cu")
		(at 232.334054 -109.40415)
		(property "Reference" "PD80"
			(at 1.345946 2.72542 0)
			(unlocked yes)
			(layer "F.SilkS")
			(effects
				(font
					(size 0.7874 0.5842)
					(thickness 0.1524)
				)
				(justify left)
			)
		)
		(property "Value" ""
			(at 0 0 0)
			(layer "F.Fab")
			(effects
				(font
					(size 1.27 1.27)
				)
			)
		)
		(duplicate_pad_numbers_are_jumpers no)
		(fp_line
			(start -3.656584 -1.970024)
			(end -3.656584 1.970024)
			(stroke
				(width 0.1524)
				(type default)
			)
			(layer "F.SilkS")
		)
		(fp_line
			(start -3.656584 1.970024)
			(end 4.240784 1.970024)
			(stroke
				(width 0.1524)
				(type default)
			)
			(layer "F.SilkS")
		)
		(fp_line
			(start 4.240784 -1.970024)
			(end -3.656584 -1.970024)
			(stroke
				(width 0.1524)
				(type default)
			)
			(layer "F.SilkS")
		)
		(fp_line
			(start 4.240784 1.970024)
			(end 4.240784 -1.970024)
			(stroke
				(width 0.1524)
				(type default)
			)
			(layer "F.SilkS")
		)
		(fp_poly
			(pts
				(xy 3.580384 1.970024) (xy 3.580384 -1.970024) (xy 4.240784 -1.970024) (xy 4.240784 1.970024)
			)
			(stroke
				(width 0)
				(type default)
			)
			(fill yes)
			(layer "F.SilkS")
		)
		(fp_line
			(start -2.3749 -1.970024)
			(end -2.3749 1.970024)
			(stroke
				(width 0.1)
				(type default)
			)
			(layer "F.Fab")
		)
		(fp_line
			(start -2.3749 1.970024)
			(end 2.3749 1.970024)
			(stroke
				(width 0.1)
				(type default)
			)
			(layer "F.Fab")
		)
		(fp_line
			(start 2.3749 -1.970024)
			(end -2.3749 -1.970024)
			(stroke
				(width 0.1)
				(type default)
			)
			(layer "F.Fab")
		)
		(fp_line
			(start 2.3749 1.970024)
			(end 2.3749 -1.970024)
			(stroke
				(width 0.1)
				(type default)
			)
			(layer "F.Fab")
		)
		(fp_text user "+"
			(at -4.9784 -0.23495 0)
			(unlocked yes)
			(layer "F.Fab")
			(effects
				(font
					(size 1.905 1.4224)
					(thickness 0.1524)
				)
				(justify left)
			)
		)
		(fp_text user "-"
			(at 4.1656 -0.23495 0)
			(unlocked yes)
			(layer "F.Fab")
			(effects
				(font
					(size 1.905 1.4224)
					(thickness 0.1524)
				)
				(justify left)
			)
		)
		(pad "A" smd rect
			(at -2.450084 0)
			(size 2.159 2.2606)
			(layers "F.Cu" "F.Mask" "F.Paste")
			(net "GND")
		)
		(pad "C" smd rect
			(at 2.450084 0)
			(size 2.159 2.2606)
			(layers "F.Cu" "F.Mask" "F.Paste")
			(net "P12V_AUX")
		)
	)
)
